(kicad_pcb
	(version 20260206)
	(generator "pcbnew")
	(generator_version "10.0")
	(general
		(thickness 1.6)
		(legacy_teardrops no)
	)
	(paper "A4")
	(title_block
		(title "Bryce Canyon_IOM_M2_16342-2_OCP.brd")
		(comment 1 "Bryce Canyon / footprint 69 of 1146 (U2), pads 228-345 of 456")
	)
	(layers
		(0 "F.Cu" signal "TOP")
		(4 "In1.Cu" signal "L2GND")
		(6 "In2.Cu" signal "L3")
		(8 "In3.Cu" signal "L4VCC")
		(10 "In4.Cu" signal "L5VCC")
		(12 "In5.Cu" signal "L6")
		(14 "In6.Cu" signal "L7GND")
		(2 "B.Cu" signal "BOTTOM")
		(9 "F.Adhes" user "F.Adhesive")
		(11 "B.Adhes" user "B.Adhesive")
		(13 "F.Paste" user "Package Geometry/Pastemask Top")
		(15 "B.Paste" user "Package Geometry/Pastemask Bottom")
		(5 "F.SilkS" user "Ref Des/Silkscreen Top")
		(7 "B.SilkS" user "Ref Des/Silkscreen Bottom")
		(1 "F.Mask" user "Board Geometry/Soldermask Top")
		(3 "B.Mask" user "Board Geometry/Soldermask Bottom")
		(17 "Dwgs.User" user "User.Drawings")
		(19 "Cmts.User" user "User.Comments")
		(21 "Eco1.User" user "User.Eco1")
		(23 "Eco2.User" user "User.Eco2")
		(25 "Edge.Cuts" user "Board Geometry/Outline")
		(27 "Margin" user)
		(31 "F.CrtYd" user "Package Geometry/Place Bound Top")
		(29 "B.CrtYd" user "Package Geometry/Place Bound Bottom")
		(35 "F.Fab" user "Ref Des/Assembly Top")
		(33 "B.Fab" user "Ref Des/Assembly Bottom")
	)
	(footprint ""
		(layer "F.Cu")
		(at 47.69993 -144.999964 -90)
		(property "Reference" "U2"
			(at 0 0 270)
			(layer "F.SilkS")
			(hide yes)
			(effects
				(font
					(size 1.27 1.27)
				)
			)
		)
		(property "Value" "AST2500A2-GP-GP-U"
			(at -17.0307 -8.584692 270)
			(unlocked yes)
			(layer "F.Fab")
			(hide yes)
			(effects
				(font
					(size 1.016 1.016)
					(thickness 0.1524)
				)
			)
		)
		(property "Device Type" "BGA456D19H58"
			(at -17.0307 -10.108692 270)
			(unlocked yes)
			(layer "F.Fab")
			(hide yes)
			(effects
				(font
					(size 1.016 1.016)
					(thickness 0.1524)
				)
			)
		)
		(duplicate_pad_numbers_are_jumpers no)
		(pad "J18" smd circle
			(at 5.199888 -1.999996 270)
			(size 0.3556 0.3556)
			(layers "F.Cu" "F.Mask" "F.Paste")
			(net "SCC_RMT_FULLPWR_EN")
		)
		(pad "J19" smd circle
			(at 5.999988 -1.999996 270)
			(size 0.3556 0.3556)
			(layers "F.Cu" "F.Mask" "F.Paste")
			(net "SCC_LOC_FULLPWR_EN")
		)
		(pad "J20" smd circle
			(at 6.800088 -1.999996 270)
			(size 0.3556 0.3556)
			(layers "F.Cu" "F.Mask" "F.Paste")
			(net "M2_1_ALERT#_R")
		)
		(pad "J21" smd circle
			(at 7.599934 -1.999996 270)
			(size 0.3556 0.3556)
			(layers "F.Cu" "F.Mask" "F.Paste")
			(net "GND")
		)
		(pad "J22" smd circle
			(at 8.400034 -1.999996 270)
			(size 0.3556 0.3556)
			(layers "F.Cu" "F.Mask" "F.Paste")
			(net "GND")
		)
		(pad "K1" smd circle
			(at -8.400034 -1.199896 270)
			(size 0.3556 0.3556)
			(layers "F.Cu" "F.Mask" "F.Paste")
			(net "UART_BMC_R_TX")
		)
		(pad "K2" smd circle
			(at -7.599934 -1.199896 270)
			(size 0.3556 0.3556)
			(layers "F.Cu" "F.Mask" "F.Paste")
			(net "UART_BMC_R_RX")
		)
		(pad "K3" smd circle
			(at -6.800088 -1.199896 270)
			(size 0.3556 0.3556)
			(layers "F.Cu" "F.Mask" "F.Paste")
			(net "BMC_ENTEST")
		)
		(pad "K4" smd circle
			(at -5.999988 -1.199896 270)
			(size 0.3556 0.3556)
			(layers "F.Cu" "F.Mask" "F.Paste")
			(net "DACRSET")
		)
		(pad "K5" smd circle
			(at -5.199888 -1.199896 270)
			(size 0.3556 0.3556)
			(layers "F.Cu" "F.Mask" "F.Paste")
			(net "DACAV33")
		)
		(pad "K6" smd circle
			(at -4.400042 -1.199896 270)
			(size 0.3556 0.3556)
			(layers "F.Cu" "F.Mask" "F.Paste")
			(net "DACAV33")
		)
		(pad "K7" smd circle
			(at -3.599942 -1.199896 270)
			(size 0.3556 0.3556)
			(layers "F.Cu" "F.Mask" "F.Paste")
			(net "P3V3_STBY")
		)
		(pad "K9" smd circle
			(at -1.999996 -1.199896 270)
			(size 0.3556 0.3556)
			(layers "F.Cu" "F.Mask" "F.Paste")
			(net "GND")
		)
		(pad "K10" smd circle
			(at -1.199896 -1.199896 270)
			(size 0.3556 0.3556)
			(layers "F.Cu" "F.Mask" "F.Paste")
			(net "GND")
		)
		(pad "K11" smd circle
			(at -0.40005 -1.199896 270)
			(size 0.3556 0.3556)
			(layers "F.Cu" "F.Mask" "F.Paste")
			(net "GND")
		)
		(pad "K12" smd circle
			(at 0.40005 -1.199896 270)
			(size 0.3556 0.3556)
			(layers "F.Cu" "F.Mask" "F.Paste")
			(net "GND")
		)
		(pad "K13" smd circle
			(at 1.199896 -1.199896 270)
			(size 0.3556 0.3556)
			(layers "F.Cu" "F.Mask" "F.Paste")
			(net "GND")
		)
		(pad "K14" smd circle
			(at 1.999996 -1.199896 270)
			(size 0.3556 0.3556)
			(layers "F.Cu" "F.Mask" "F.Paste")
			(net "GND")
		)
		(pad "K16" smd circle
			(at 3.599942 -1.199896 270)
			(size 0.3556 0.3556)
			(layers "F.Cu" "F.Mask" "F.Paste")
			(net "GND")
		)
		(pad "K17" smd circle
			(at 4.400042 -1.199896 270)
			(size 0.3556 0.3556)
			(layers "F.Cu" "F.Mask" "F.Paste")
			(net "P1V8_STBY")
		)
		(pad "K18" smd circle
			(at 5.199888 -1.199896 270)
			(size 0.3556 0.3556)
			(layers "F.Cu" "F.Mask" "F.Paste")
			(net "Net_555")
		)
		(pad "K19" smd circle
			(at 5.999988 -1.199896 270)
			(size 0.3556 0.3556)
			(layers "F.Cu" "F.Mask" "F.Paste")
			(net "Net_554")
		)
		(pad "K20" smd circle
			(at 6.800088 -1.199896 270)
			(size 0.3556 0.3556)
			(layers "F.Cu" "F.Mask" "F.Paste")
			(net "BMC_PEREXT")
		)
		(pad "K21" smd circle
			(at 7.599934 -1.199896 270)
			(size 0.3556 0.3556)
			(layers "F.Cu" "F.Mask" "F.Paste")
			(net "GND")
		)
		(pad "K22" smd circle
			(at 8.400034 -1.199896 270)
			(size 0.3556 0.3556)
			(layers "F.Cu" "F.Mask" "F.Paste")
			(net "GND")
		)
		(pad "L1" smd circle
			(at -8.400034 -0.40005 270)
			(size 0.3556 0.3556)
			(layers "F.Cu" "F.Mask" "F.Paste")
			(net "BMC_SMB6_CLK")
		)
		(pad "L2" smd circle
			(at -7.599934 -0.40005 270)
			(size 0.3556 0.3556)
			(layers "F.Cu" "F.Mask" "F.Paste")
			(net "BOARD_REV_1")
		)
		(pad "L3" smd circle
			(at -6.800088 -0.40005 270)
			(size 0.3556 0.3556)
			(layers "F.Cu" "F.Mask" "F.Paste")
			(net "BMC_SMB5_CLK")
		)
		(pad "L4" smd circle
			(at -5.999988 -0.40005 270)
			(size 0.3556 0.3556)
			(layers "F.Cu" "F.Mask" "F.Paste")
			(net "BMC_SMB5_DAT")
		)
		(pad "L5" smd circle
			(at -5.199888 -0.40005 270)
			(size 0.3556 0.3556)
			(layers "F.Cu" "F.Mask" "F.Paste")
			(net "V1PLLAV11")
		)
		(pad "L6" smd circle
			(at -4.400042 -0.40005 270)
			(size 0.3556 0.3556)
			(layers "F.Cu" "F.Mask" "F.Paste")
			(net "V1PLLAV11")
		)
		(pad "L7" smd circle
			(at -3.599942 -0.40005 270)
			(size 0.3556 0.3556)
			(layers "F.Cu" "F.Mask" "F.Paste")
			(net "P1V15_STBY")
		)
		(pad "L9" smd circle
			(at -1.999996 -0.40005 270)
			(size 0.3556 0.3556)
			(layers "F.Cu" "F.Mask" "F.Paste")
			(net "GND")
		)
		(pad "L10" smd circle
			(at -1.199896 -0.40005 270)
			(size 0.3556 0.3556)
			(layers "F.Cu" "F.Mask" "F.Paste")
			(net "GND")
		)
		(pad "L11" smd circle
			(at -0.40005 -0.40005 270)
			(size 0.3556 0.3556)
			(layers "F.Cu" "F.Mask" "F.Paste")
			(net "GND")
		)
		(pad "L12" smd circle
			(at 0.40005 -0.40005 270)
			(size 0.3556 0.3556)
			(layers "F.Cu" "F.Mask" "F.Paste")
			(net "GND")
		)
		(pad "L13" smd circle
			(at 1.199896 -0.40005 270)
			(size 0.3556 0.3556)
			(layers "F.Cu" "F.Mask" "F.Paste")
			(net "GND")
		)
		(pad "L14" smd circle
			(at 1.999996 -0.40005 270)
			(size 0.3556 0.3556)
			(layers "F.Cu" "F.Mask" "F.Paste")
			(net "GND")
		)
		(pad "L16" smd circle
			(at 3.599942 -0.40005 270)
			(size 0.3556 0.3556)
			(layers "F.Cu" "F.Mask" "F.Paste")
			(net "P3V3_STBY")
		)
		(pad "L17" smd circle
			(at 4.400042 -0.40005 270)
			(size 0.3556 0.3556)
			(layers "F.Cu" "F.Mask" "F.Paste")
			(net "P1V15_STBY")
		)
		(pad "L18" smd circle
			(at 5.199888 -0.40005 270)
			(size 0.3556 0.3556)
			(layers "F.Cu" "F.Mask" "F.Paste")
			(net "Net_553")
		)
		(pad "L19" smd circle
			(at 5.999988 -0.40005 270)
			(size 0.3556 0.3556)
			(layers "F.Cu" "F.Mask" "F.Paste")
			(net "Net_552")
		)
		(pad "L20" smd circle
			(at 6.800088 -0.40005 270)
			(size 0.3556 0.3556)
			(layers "F.Cu" "F.Mask" "F.Paste")
			(net "PD_PERST_N")
		)
		(pad "L21" smd circle
			(at 7.599934 -0.40005 270)
			(size 0.3556 0.3556)
			(layers "F.Cu" "F.Mask" "F.Paste")
			(net "Net_551")
		)
		(pad "L22" smd circle
			(at 8.400034 -0.40005 270)
			(size 0.3556 0.3556)
			(layers "F.Cu" "F.Mask" "F.Paste")
			(net "Net_550")
		)
		(pad "M1" smd circle
			(at -8.400034 0.40005 270)
			(size 0.3556 0.3556)
			(layers "F.Cu" "F.Mask" "F.Paste")
			(net "GND")
		)
		(pad "M2" smd circle
			(at -7.599934 0.40005 270)
			(size 0.3556 0.3556)
			(layers "F.Cu" "F.Mask" "F.Paste")
			(net "GND")
		)
		(pad "M3" smd circle
			(at -6.800088 0.40005 270)
			(size 0.3556 0.3556)
			(layers "F.Cu" "F.Mask" "F.Paste")
			(net "GND")
		)
		(pad "M4" smd circle
			(at -5.999988 0.40005 270)
			(size 0.3556 0.3556)
			(layers "F.Cu" "F.Mask" "F.Paste")
			(net "GND")
		)
		(pad "M5" smd circle
			(at -5.199888 0.40005 270)
			(size 0.3556 0.3556)
			(layers "F.Cu" "F.Mask" "F.Paste")
			(net "GND")
		)
		(pad "M6" smd circle
			(at -4.400042 0.40005 270)
			(size 0.3556 0.3556)
			(layers "F.Cu" "F.Mask" "F.Paste")
			(net "GND")
		)
		(pad "M7" smd circle
			(at -3.599942 0.40005 270)
			(size 0.3556 0.3556)
			(layers "F.Cu" "F.Mask" "F.Paste")
			(net "GND")
		)
		(pad "M9" smd circle
			(at -1.999996 0.40005 270)
			(size 0.3556 0.3556)
			(layers "F.Cu" "F.Mask" "F.Paste")
			(net "GND")
		)
		(pad "M10" smd circle
			(at -1.199896 0.40005 270)
			(size 0.3556 0.3556)
			(layers "F.Cu" "F.Mask" "F.Paste")
			(net "GND")
		)
		(pad "M11" smd circle
			(at -0.40005 0.40005 270)
			(size 0.3556 0.3556)
			(layers "F.Cu" "F.Mask" "F.Paste")
			(net "GND")
		)
		(pad "M12" smd circle
			(at 0.40005 0.40005 270)
			(size 0.3556 0.3556)
			(layers "F.Cu" "F.Mask" "F.Paste")
			(net "GND")
		)
		(pad "M13" smd circle
			(at 1.199896 0.40005 270)
			(size 0.3556 0.3556)
			(layers "F.Cu" "F.Mask" "F.Paste")
			(net "GND")
		)
		(pad "M14" smd circle
			(at 1.999996 0.40005 270)
			(size 0.3556 0.3556)
			(layers "F.Cu" "F.Mask" "F.Paste")
			(net "GND")
		)
		(pad "M16" smd circle
			(at 3.599942 0.40005 270)
			(size 0.3556 0.3556)
			(layers "F.Cu" "F.Mask" "F.Paste")
			(net "GND")
		)
		(pad "M17" smd circle
			(at 4.400042 0.40005 270)
			(size 0.3556 0.3556)
			(layers "F.Cu" "F.Mask" "F.Paste")
			(net "GND")
		)
		(pad "M18" smd circle
			(at 5.199888 0.40005 270)
			(size 0.3556 0.3556)
			(layers "F.Cu" "F.Mask" "F.Paste")
			(net "BMC_SMB1_CLK")
		)
		(pad "M19" smd circle
			(at 5.999988 0.40005 270)
			(size 0.3556 0.3556)
			(layers "F.Cu" "F.Mask" "F.Paste")
			(net "BMC_SMB1_DAT")
		)
		(pad "M20" smd circle
			(at 6.800088 0.40005 270)
			(size 0.3556 0.3556)
			(layers "F.Cu" "F.Mask" "F.Paste")
			(net "BMC_SMB2_CLK")
		)
		(pad "M21" smd circle
			(at 7.599934 0.40005 270)
			(size 0.3556 0.3556)
			(layers "F.Cu" "F.Mask" "F.Paste")
			(net "GND")
		)
		(pad "M22" smd circle
			(at 8.400034 0.40005 270)
			(size 0.3556 0.3556)
			(layers "F.Cu" "F.Mask" "F.Paste")
			(net "GND")
		)
		(pad "N1" smd circle
			(at -8.400034 1.199896 270)
			(size 0.3556 0.3556)
			(layers "F.Cu" "F.Mask" "F.Paste")
			(net "BMC_SMB7_CLK")
		)
		(pad "N2" smd circle
			(at -7.599934 1.199896 270)
			(size 0.3556 0.3556)
			(layers "F.Cu" "F.Mask" "F.Paste")
			(net "BMC_SMB6_DAT")
		)
		(pad "N3" smd circle
			(at -6.800088 1.199896 270)
			(size 0.3556 0.3556)
			(layers "F.Cu" "F.Mask" "F.Paste")
			(net "BOARD_REV_2")
		)
		(pad "N4" smd circle
			(at -5.999988 1.199896 270)
			(size 0.3556 0.3556)
			(layers "F.Cu" "F.Mask" "F.Paste")
			(net "PCIE_WAKE_N")
		)
		(pad "N5" smd circle
			(at -5.199888 1.199896 270)
			(size 0.3556 0.3556)
			(layers "F.Cu" "F.Mask" "F.Paste")
			(net "IOM_TYPE0")
		)
		(pad "N6" smd circle
			(at -4.400042 1.199896 270)
			(size 0.3556 0.3556)
			(layers "F.Cu" "F.Mask" "F.Paste")
			(net "P3V3_STBY")
		)
		(pad "N7" smd circle
			(at -3.599942 1.199896 270)
			(size 0.3556 0.3556)
			(layers "F.Cu" "F.Mask" "F.Paste")
			(net "P1V15_STBY")
		)
		(pad "N9" smd circle
			(at -1.999996 1.199896 270)
			(size 0.3556 0.3556)
			(layers "F.Cu" "F.Mask" "F.Paste")
			(net "GND")
		)
		(pad "N10" smd circle
			(at -1.199896 1.199896 270)
			(size 0.3556 0.3556)
			(layers "F.Cu" "F.Mask" "F.Paste")
			(net "GND")
		)
		(pad "N11" smd circle
			(at -0.40005 1.199896 270)
			(size 0.3556 0.3556)
			(layers "F.Cu" "F.Mask" "F.Paste")
			(net "GND")
		)
		(pad "N12" smd circle
			(at 0.40005 1.199896 270)
			(size 0.3556 0.3556)
			(layers "F.Cu" "F.Mask" "F.Paste")
			(net "GND")
		)
		(pad "N13" smd circle
			(at 1.199896 1.199896 270)
			(size 0.3556 0.3556)
			(layers "F.Cu" "F.Mask" "F.Paste")
			(net "GND")
		)
		(pad "N14" smd circle
			(at 1.999996 1.199896 270)
			(size 0.3556 0.3556)
			(layers "F.Cu" "F.Mask" "F.Paste")
			(net "GND")
		)
		(pad "N16" smd circle
			(at 3.599942 1.199896 270)
			(size 0.3556 0.3556)
			(layers "F.Cu" "F.Mask" "F.Paste")
			(net "P1V15_STBY")
		)
		(pad "N17" smd circle
			(at 4.400042 1.199896 270)
			(size 0.3556 0.3556)
			(layers "F.Cu" "F.Mask" "F.Paste")
			(net "P3V3_STBY")
		)
		(pad "N18" smd circle
			(at 5.199888 1.199896 270)
			(size 0.3556 0.3556)
			(layers "F.Cu" "F.Mask" "F.Paste")
			(net "I2C_MEZZ_ALERT_N")
		)
		(pad "N19" smd circle
			(at 5.999988 1.199896 270)
			(size 0.3556 0.3556)
			(layers "F.Cu" "F.Mask" "F.Paste")
			(net "IOM_LOC_INS_N")
		)
		(pad "N20" smd circle
			(at 6.800088 1.199896 270)
			(size 0.3556 0.3556)
			(layers "F.Cu" "F.Mask" "F.Paste")
			(net "Net_549")
		)
		(pad "N21" smd circle
			(at 7.599934 1.199896 270)
			(size 0.3556 0.3556)
			(layers "F.Cu" "F.Mask" "F.Paste")
			(net "BMC_SMB14_CLK")
		)
		(pad "N22" smd circle
			(at 8.400034 1.199896 270)
			(size 0.3556 0.3556)
			(layers "F.Cu" "F.Mask" "F.Paste")
			(net "BMC_SMB14_DAT")
		)
		(pad "P1" smd circle
			(at -8.400034 1.999996 270)
			(size 0.3556 0.3556)
			(layers "F.Cu" "F.Mask" "F.Paste")
			(net "BMC_SMB7_DAT")
		)
		(pad "P2" smd circle
			(at -7.599934 1.999996 270)
			(size 0.3556 0.3556)
			(layers "F.Cu" "F.Mask" "F.Paste")
			(net "BMC_SMB8_CLK")
		)
		(pad "P3" smd circle
			(at -6.800088 1.999996 270)
			(size 0.3556 0.3556)
			(layers "F.Cu" "F.Mask" "F.Paste")
			(net "TP_BMC_GPIOL5")
		)
		(pad "P4" smd circle
			(at -5.999988 1.999996 270)
			(size 0.3556 0.3556)
			(layers "F.Cu" "F.Mask" "F.Paste")
			(net "TP_BMC_GPIOL4")
		)
		(pad "P5" smd circle
			(at -5.199888 1.999996 270)
			(size 0.3556 0.3556)
			(layers "F.Cu" "F.Mask" "F.Paste")
			(net "Net_560")
		)
		(pad "P6" smd circle
			(at -4.400042 1.999996 270)
			(size 0.3556 0.3556)
			(layers "F.Cu" "F.Mask" "F.Paste")
			(net "P3V3_STBY")
		)
		(pad "P7" smd circle
			(at -3.599942 1.999996 270)
			(size 0.3556 0.3556)
			(layers "F.Cu" "F.Mask" "F.Paste")
			(net "P1V15_STBY")
		)
		(pad "P9" smd circle
			(at -1.999996 1.999996 270)
			(size 0.3556 0.3556)
			(layers "F.Cu" "F.Mask" "F.Paste")
			(net "P1V15_STBY")
		)
		(pad "P10" smd circle
			(at -1.199896 1.999996 270)
			(size 0.3556 0.3556)
			(layers "F.Cu" "F.Mask" "F.Paste")
			(net "P1V15_STBY")
		)
		(pad "P11" smd circle
			(at -0.40005 1.999996 270)
			(size 0.3556 0.3556)
			(layers "F.Cu" "F.Mask" "F.Paste")
			(net "P1V15_STBY")
		)
		(pad "P12" smd circle
			(at 0.40005 1.999996 270)
			(size 0.3556 0.3556)
			(layers "F.Cu" "F.Mask" "F.Paste")
			(net "P1V15_STBY")
		)
		(pad "P13" smd circle
			(at 1.199896 1.999996 270)
			(size 0.3556 0.3556)
			(layers "F.Cu" "F.Mask" "F.Paste")
			(net "P1V15_STBY")
		)
		(pad "P14" smd circle
			(at 1.999996 1.999996 270)
			(size 0.3556 0.3556)
			(layers "F.Cu" "F.Mask" "F.Paste")
			(net "P1V15_STBY")
		)
		(pad "P16" smd circle
			(at 3.599942 1.999996 270)
			(size 0.3556 0.3556)
			(layers "F.Cu" "F.Mask" "F.Paste")
			(net "P1V15_STBY")
		)
		(pad "P17" smd circle
			(at 4.400042 1.999996 270)
			(size 0.3556 0.3556)
			(layers "F.Cu" "F.Mask" "F.Paste")
			(net "P3V3_STBY")
		)
		(pad "P18" smd circle
			(at 5.199888 1.999996 270)
			(size 0.3556 0.3556)
			(layers "F.Cu" "F.Mask" "F.Paste")
			(net "Net_3")
		)
		(pad "P19" smd circle
			(at 5.999988 1.999996 270)
			(size 0.3556 0.3556)
			(layers "F.Cu" "F.Mask" "F.Paste")
			(net "IOM_FULL_PWR_EN_R")
		)
		(pad "P20" smd circle
			(at 6.800088 1.999996 270)
			(size 0.3556 0.3556)
			(layers "F.Cu" "F.Mask" "F.Paste")
			(net "BMC_SMB2_DAT")
		)
		(pad "P21" smd circle
			(at 7.599934 1.999996 270)
			(size 0.3556 0.3556)
			(layers "F.Cu" "F.Mask" "F.Paste")
			(net "BMC_GPIOY3")
		)
		(pad "P22" smd circle
			(at 8.400034 1.999996 270)
			(size 0.3556 0.3556)
			(layers "F.Cu" "F.Mask" "F.Paste")
			(net "BMC_GPIOY2")
		)
		(pad "R1" smd circle
			(at -8.400034 2.800096 270)
			(size 0.3556 0.3556)
			(layers "F.Cu" "F.Mask" "F.Paste")
			(net "BMC_SMB8_DAT")
		)
		(pad "R2" smd circle
			(at -7.599934 2.800096 270)
			(size 0.3556 0.3556)
			(layers "F.Cu" "F.Mask" "F.Paste")
			(net "BOARD_REV_0")
		)
		(pad "R3" smd circle
			(at -6.800088 2.800096 270)
			(size 0.3556 0.3556)
			(layers "F.Cu" "F.Mask" "F.Paste")
			(net "IOM_TYPE2")
		)
		(pad "R4" smd circle
			(at -5.999988 2.800096 270)
			(size 0.3556 0.3556)
			(layers "F.Cu" "F.Mask" "F.Paste")
			(net "IOM_TYPE1")
		)
		(pad "R5" smd circle
			(at -5.199888 2.800096 270)
			(size 0.3556 0.3556)
			(layers "F.Cu" "F.Mask" "F.Paste")
			(net "UART_EXP_BMC_RX_R")
		)
		(pad "R6" smd circle
			(at -4.400042 2.800096 270)
			(size 0.3556 0.3556)
			(layers "F.Cu" "F.Mask" "F.Paste")
			(net "P3V3_STBY")
		)
		(pad "R7" smd circle
			(at -3.599942 2.800096 270)
			(size 0.3556 0.3556)
			(layers "F.Cu" "F.Mask" "F.Paste")
			(net "P1V15_STBY")
		)
		(pad "R16" smd circle
			(at 3.599942 2.800096 270)
			(size 0.3556 0.3556)
			(layers "F.Cu" "F.Mask" "F.Paste")
			(net "P1V15_STBY")
		)
		(pad "R17" smd circle
			(at 4.400042 2.800096 270)
			(size 0.3556 0.3556)
			(layers "F.Cu" "F.Mask" "F.Paste")
			(net "P3V3_STBY")
		)
		(pad "R18" smd circle
			(at 5.199888 2.800096 270)
			(size 0.3556 0.3556)
			(layers "F.Cu" "F.Mask" "F.Paste")
			(net "BMC_UART_SEL_IN")
		)
		(pad "R19" smd circle
			(at 5.999988 2.800096 270)
			(size 0.3556 0.3556)
			(layers "F.Cu" "F.Mask" "F.Paste")
			(net "BMC_GPIOS4")
		)
		(pad "R20" smd circle
			(at 6.800088 2.800096 270)
			(size 0.3556 0.3556)
			(layers "F.Cu" "F.Mask" "F.Paste")
			(net "Net_108")
		)
		(pad "R21" smd circle
			(at 7.599934 2.800096 270)
			(size 0.3556 0.3556)
			(layers "F.Cu" "F.Mask" "F.Paste")
			(net "BMC_GPIOY1")
		)
	)
)
